(kicad_pcb
	(version 20260206)
	(generator "pcbnew")
	(generator_version "10.0")
	(general
		(thickness 1.6)
		(legacy_teardrops no)
	)
	(paper "A4")
	(title_block
		(title "v1-pdb — T6M_PDB_D_0927_0900.brd")
		(comment 1 "Open CloudServer (Microsoft) / footprint 308 of 321 (J12), pads 1-46 of 46")
	)
	(layers
		(0 "F.Cu" signal "TOP")
		(4 "In1.Cu" signal "GND")
		(6 "In2.Cu" signal "IN1")
		(8 "In3.Cu" signal "VCC")
		(10 "In4.Cu" signal "VCC1")
		(12 "In5.Cu" signal "IN2")
		(14 "In6.Cu" signal "GND1")
		(2 "B.Cu" signal "BOTTOM")
		(9 "F.Adhes" user "F.Adhesive")
		(11 "B.Adhes" user "B.Adhesive")
		(13 "F.Paste" user "Package Geometry/Pastemask Top")
		(15 "B.Paste" user "Package Geometry/Pastemask Bottom")
		(5 "F.SilkS" user "Ref Des/Silkscreen Top")
		(7 "B.SilkS" user "Ref Des/Silkscreen Bottom")
		(1 "F.Mask" user "Board Geometry/Soldermask Top")
		(3 "B.Mask" user "Board Geometry/Soldermask Bottom")
		(17 "Dwgs.User" user "User.Drawings")
		(19 "Cmts.User" user "User.Comments")
		(21 "Eco1.User" user "User.Eco1")
		(23 "Eco2.User" user "User.Eco2")
		(25 "Edge.Cuts" user "Board Geometry/Outline")
		(27 "Margin" user)
		(31 "F.CrtYd" user "Package Geometry/Place Bound Top")
		(29 "B.CrtYd" user "Package Geometry/Place Bound Bottom")
		(35 "F.Fab" user "Ref Des/Assembly Top")
		(33 "B.Fab" user "Ref Des/Assembly Bottom")
	)
	(footprint ""
		(layer "B.Cu")
		(at 44.03979 -230.51008 90)
		(property "Reference" "J12"
			(at 6.153658 -3.773932 0)
			(unlocked yes)
			(layer "B.SilkS")
			(effects
				(font
					(size 0.7874 0.5842)
					(thickness 0.1524)
				)
				(justify left mirror)
			)
		)
		(property "Value" ""
			(at 0 0 90)
			(layer "B.Fab")
			(effects
				(font
					(size 1.27 1.27)
				)
				(justify mirror)
			)
		)
		(duplicate_pad_numbers_are_jumpers no)
		(pad "" np_thru_hole circle
			(at -1.35001 -2.54)
			(size 2.5146 2.5146)
			(drill 2.5146)
			(layers "*.Cu" "*.Mask")
			(clearance 0.381)
			(thermal_gap 0.381)
		)
		(pad "" np_thru_hole circle
			(at 0 50.8)
			(size 2.5146 2.5146)
			(drill 2.5146)
			(layers "*.Cu" "*.Mask")
			(clearance 0.381)
			(thermal_gap 0.381)
		)
		(pad "P1" thru_hole rect
			(at 0 0)
			(size 1.1684 1.1684)
			(drill 0.762)
			(layers "*.Cu" "*.Mask")
			(remove_unused_layers no)
			(net "GND")
			(clearance 0.0508)
			(padstack
				(mode front_inner_back)
				(layer "Inner"
					(shape circle)
					(size 1.1684 1.1684)
					(clearance 0.0508)
				)
				(layer "B.Cu"
					(shape rect)
					(size 1.1684 1.1684)
					(thermal_gap 0.0508)
					(clearance 0.0508)
				)
			)
		)
		(pad "P2" thru_hole circle
			(at 0 2.54)
			(size 1.1684 1.1684)
			(drill 0.762)
			(layers "*.Cu" "*.Mask")
			(remove_unused_layers no)
			(net "GND")
			(clearance 0.0508)
			(thermal_gap 0.0508)
		)
		(pad "P3" thru_hole circle
			(at 0 5.08)
			(size 1.1684 1.1684)
			(drill 0.762)
			(layers "*.Cu" "*.Mask")
			(remove_unused_layers no)
			(net "GND")
			(clearance 0.0508)
			(thermal_gap 0.0508)
		)
		(pad "P4" thru_hole circle
			(at 0 7.62)
			(size 1.1684 1.1684)
			(drill 0.762)
			(layers "*.Cu" "*.Mask")
			(remove_unused_layers no)
			(net "GND")
			(clearance 0.0508)
			(thermal_gap 0.0508)
		)
		(pad "P5" thru_hole circle
			(at 0 10.16)
			(size 1.1684 1.1684)
			(drill 0.762)
			(layers "*.Cu" "*.Mask")
			(remove_unused_layers no)
			(net "GND")
			(clearance 0.0508)
			(thermal_gap 0.0508)
		)
		(pad "P6" thru_hole circle
			(at 0 12.7)
			(size 1.1684 1.1684)
			(drill 0.762)
			(layers "*.Cu" "*.Mask")
			(remove_unused_layers no)
			(net "GND")
			(clearance 0.0508)
			(thermal_gap 0.0508)
		)
		(pad "P7" thru_hole circle
			(at 0 15.24)
			(size 1.1684 1.1684)
			(drill 0.762)
			(layers "*.Cu" "*.Mask")
			(remove_unused_layers no)
			(net "GND")
			(clearance 0.0508)
			(thermal_gap 0.0508)
		)
		(pad "P8" thru_hole circle
			(at 0 17.78)
			(size 1.1684 1.1684)
			(drill 0.762)
			(layers "*.Cu" "*.Mask")
			(remove_unused_layers no)
			(net "GND")
			(clearance 0.0508)
			(thermal_gap 0.0508)
		)
		(pad "P9" thru_hole circle
			(at 0 20.32)
			(size 1.1684 1.1684)
			(drill 0.762)
			(layers "*.Cu" "*.Mask")
			(remove_unused_layers no)
			(net "P12V")
			(clearance 0.0508)
			(thermal_gap 0.0508)
		)
		(pad "P10" thru_hole circle
			(at 0 22.86)
			(size 1.1684 1.1684)
			(drill 0.762)
			(layers "*.Cu" "*.Mask")
			(remove_unused_layers no)
			(net "P12V")
			(clearance 0.0508)
			(thermal_gap 0.0508)
		)
		(pad "P11" thru_hole circle
			(at 0 25.4)
			(size 1.1684 1.1684)
			(drill 0.762)
			(layers "*.Cu" "*.Mask")
			(remove_unused_layers no)
			(net "P12V")
			(clearance 0.0508)
			(thermal_gap 0.0508)
		)
		(pad "P12" thru_hole circle
			(at 0 27.94)
			(size 1.1684 1.1684)
			(drill 0.762)
			(layers "*.Cu" "*.Mask")
			(remove_unused_layers no)
			(net "P12V")
			(clearance 0.0508)
			(thermal_gap 0.0508)
		)
		(pad "P13" thru_hole circle
			(at 0 30.48)
			(size 1.1684 1.1684)
			(drill 0.762)
			(layers "*.Cu" "*.Mask")
			(remove_unused_layers no)
			(net "P12V")
			(clearance 0.0508)
			(thermal_gap 0.0508)
		)
		(pad "P14" thru_hole circle
			(at 0 33.02)
			(size 1.1684 1.1684)
			(drill 0.762)
			(layers "*.Cu" "*.Mask")
			(remove_unused_layers no)
			(net "P12V")
			(clearance 0.0508)
			(thermal_gap 0.0508)
		)
		(pad "P15" thru_hole circle
			(at 0 35.56)
			(size 1.1684 1.1684)
			(drill 0.762)
			(layers "*.Cu" "*.Mask")
			(remove_unused_layers no)
			(net "P12V")
			(clearance 0.0508)
			(thermal_gap 0.0508)
		)
		(pad "P16" thru_hole circle
			(at 0 38.1)
			(size 1.1684 1.1684)
			(drill 0.762)
			(layers "*.Cu" "*.Mask")
			(remove_unused_layers no)
			(net "P12V")
			(clearance 0.0508)
			(thermal_gap 0.0508)
		)
		(pad "P17" thru_hole circle
			(at -2.70002 38.1)
			(size 1.1684 1.1684)
			(drill 0.762)
			(layers "*.Cu" "*.Mask")
			(remove_unused_layers no)
			(net "P12V")
			(clearance 0.0508)
			(thermal_gap 0.0508)
		)
		(pad "P18" thru_hole circle
			(at -2.70002 35.56)
			(size 1.1684 1.1684)
			(drill 0.762)
			(layers "*.Cu" "*.Mask")
			(remove_unused_layers no)
			(net "P12V")
			(clearance 0.0508)
			(thermal_gap 0.0508)
		)
		(pad "P19" thru_hole circle
			(at -2.70002 33.02)
			(size 1.1684 1.1684)
			(drill 0.762)
			(layers "*.Cu" "*.Mask")
			(remove_unused_layers no)
			(net "P12V")
			(clearance 0.0508)
			(thermal_gap 0.0508)
		)
		(pad "P20" thru_hole circle
			(at -2.70002 30.48)
			(size 1.1684 1.1684)
			(drill 0.762)
			(layers "*.Cu" "*.Mask")
			(remove_unused_layers no)
			(net "P12V")
			(clearance 0.0508)
			(thermal_gap 0.0508)
		)
		(pad "P21" thru_hole circle
			(at -2.70002 27.94)
			(size 1.1684 1.1684)
			(drill 0.762)
			(layers "*.Cu" "*.Mask")
			(remove_unused_layers no)
			(net "P12V")
			(clearance 0.0508)
			(thermal_gap 0.0508)
		)
		(pad "P22" thru_hole circle
			(at -2.70002 25.4)
			(size 1.1684 1.1684)
			(drill 0.762)
			(layers "*.Cu" "*.Mask")
			(remove_unused_layers no)
			(net "P12V")
			(clearance 0.0508)
			(thermal_gap 0.0508)
		)
		(pad "P23" thru_hole circle
			(at -2.70002 22.86)
			(size 1.1684 1.1684)
			(drill 0.762)
			(layers "*.Cu" "*.Mask")
			(remove_unused_layers no)
			(net "P12V")
			(clearance 0.0508)
			(thermal_gap 0.0508)
		)
		(pad "P24" thru_hole circle
			(at -2.70002 20.32)
			(size 1.1684 1.1684)
			(drill 0.762)
			(layers "*.Cu" "*.Mask")
			(remove_unused_layers no)
			(net "P12V")
			(clearance 0.0508)
			(thermal_gap 0.0508)
		)
		(pad "P25" thru_hole circle
			(at -2.70002 17.78)
			(size 1.1684 1.1684)
			(drill 0.762)
			(layers "*.Cu" "*.Mask")
			(remove_unused_layers no)
			(net "GND")
			(clearance 0.0508)
			(thermal_gap 0.0508)
		)
		(pad "P26" thru_hole circle
			(at -2.70002 15.24)
			(size 1.1684 1.1684)
			(drill 0.762)
			(layers "*.Cu" "*.Mask")
			(remove_unused_layers no)
			(net "GND")
			(clearance 0.0508)
			(thermal_gap 0.0508)
		)
		(pad "P27" thru_hole circle
			(at -2.70002 12.7)
			(size 1.1684 1.1684)
			(drill 0.762)
			(layers "*.Cu" "*.Mask")
			(remove_unused_layers no)
			(net "GND")
			(clearance 0.0508)
			(thermal_gap 0.0508)
		)
		(pad "P28" thru_hole circle
			(at -2.70002 10.16)
			(size 1.1684 1.1684)
			(drill 0.762)
			(layers "*.Cu" "*.Mask")
			(remove_unused_layers no)
			(net "GND")
			(clearance 0.0508)
			(thermal_gap 0.0508)
		)
		(pad "P29" thru_hole circle
			(at -2.70002 7.62)
			(size 1.1684 1.1684)
			(drill 0.762)
			(layers "*.Cu" "*.Mask")
			(remove_unused_layers no)
			(net "GND")
			(clearance 0.0508)
			(thermal_gap 0.0508)
		)
		(pad "P30" thru_hole circle
			(at -2.70002 5.08)
			(size 1.1684 1.1684)
			(drill 0.762)
			(layers "*.Cu" "*.Mask")
			(remove_unused_layers no)
			(net "GND")
			(clearance 0.0508)
			(thermal_gap 0.0508)
		)
		(pad "P31" thru_hole circle
			(at -2.70002 2.54)
			(size 1.1684 1.1684)
			(drill 0.762)
			(layers "*.Cu" "*.Mask")
			(remove_unused_layers no)
			(net "GND")
			(clearance 0.0508)
			(thermal_gap 0.0508)
		)
		(pad "P32" thru_hole circle
			(at -2.70002 0)
			(size 1.1684 1.1684)
			(drill 0.762)
			(layers "*.Cu" "*.Mask")
			(remove_unused_layers no)
			(net "GND")
			(clearance 0.0508)
			(thermal_gap 0.0508)
		)
		(pad "S1" thru_hole circle
			(at 0.55499 41.60012)
			(size 1.1684 1.1684)
			(drill 0.762)
			(layers "*.Cu" "*.Mask")
			(remove_unused_layers no)
			(net "T6_BLAD1_TXD")
			(clearance 0.0508)
			(thermal_gap 0.0508)
		)
		(pad "S2" thru_hole circle
			(at -0.71501 42.87012)
			(size 1.1684 1.1684)
			(drill 0.762)
			(layers "*.Cu" "*.Mask")
			(remove_unused_layers no)
			(net "T6_BLAD1_RXD")
			(clearance 0.0508)
			(thermal_gap 0.0508)
		)
		(pad "S3" thru_hole circle
			(at 0.55499 44.14012)
			(size 1.1684 1.1684)
			(drill 0.762)
			(layers "*.Cu" "*.Mask")
			(remove_unused_layers no)
			(net "T6_BLAD1_EN")
			(clearance 0.0508)
			(thermal_gap 0.0508)
		)
		(pad "S4" thru_hole circle
			(at -0.71501 45.41012)
			(size 1.1684 1.1684)
			(drill 0.762)
			(layers "*.Cu" "*.Mask")
			(remove_unused_layers no)
			(net "T6_BLAD2_EN")
			(clearance 0.0508)
			(thermal_gap 0.0508)
		)
		(pad "S5" thru_hole circle
			(at 0.55499 46.68012)
			(size 1.1684 1.1684)
			(drill 0.762)
			(layers "*.Cu" "*.Mask")
			(remove_unused_layers no)
			(net "T6_BLAD2_TXD")
			(clearance 0.0508)
			(thermal_gap 0.0508)
		)
		(pad "S6" thru_hole circle
			(at -0.71501 47.95012)
			(size 1.1684 1.1684)
			(drill 0.762)
			(layers "*.Cu" "*.Mask")
			(remove_unused_layers no)
			(net "T6_BLAD2_RXD")
			(clearance 0.0508)
			(thermal_gap 0.0508)
		)
		(pad "S7" thru_hole circle
			(at -3.25501 47.95012)
			(size 1.1684 1.1684)
			(drill 0.762)
			(layers "*.Cu" "*.Mask")
			(remove_unused_layers no)
			(net "T6_BLAD4_RXD")
			(clearance 0.0508)
			(thermal_gap 0.0508)
		)
		(pad "S8" thru_hole circle
			(at -1.98501 46.68012)
			(size 1.1684 1.1684)
			(drill 0.762)
			(layers "*.Cu" "*.Mask")
			(remove_unused_layers no)
			(net "T6_BLAD4_TXD")
			(clearance 0.0508)
			(thermal_gap 0.0508)
		)
		(pad "S9" thru_hole circle
			(at -3.25501 45.41012)
			(size 1.1684 1.1684)
			(drill 0.762)
			(layers "*.Cu" "*.Mask")
			(remove_unused_layers no)
			(net "T6_BLAD4_EN")
			(clearance 0.0508)
			(thermal_gap 0.0508)
		)
		(pad "S10" thru_hole circle
			(at -1.98501 44.14012)
			(size 1.1684 1.1684)
			(drill 0.762)
			(layers "*.Cu" "*.Mask")
			(remove_unused_layers no)
			(net "T6_BLAD3_EN")
			(clearance 0.0508)
			(thermal_gap 0.0508)
		)
		(pad "S11" thru_hole circle
			(at -3.25501 42.87012)
			(size 1.1684 1.1684)
			(drill 0.762)
			(layers "*.Cu" "*.Mask")
			(remove_unused_layers no)
			(net "T6_BLAD3_RXD")
			(clearance 0.0508)
			(thermal_gap 0.0508)
		)
		(pad "S12" thru_hole circle
			(at -1.98501 41.60012)
			(size 1.1684 1.1684)
			(drill 0.762)
			(layers "*.Cu" "*.Mask")
			(remove_unused_layers no)
			(net "T6_BLAD3_TXD")
			(clearance 0.0508)
			(thermal_gap 0.0508)
		)
	)
)
